(kicad_pcb
	(version 20260206)
	(generator "pcbnew")
	(generator_version "10.0")
	(general
		(thickness 1.6)
		(legacy_teardrops no)
	)
	(paper "A4")
	(title_block
		(title "Bryce Canyon_F.DPB_16315-1-OCP.brd")
		(comment 1 "Bryce Canyon / footprints 1016-1020 of 2223")
	)
	(layers
		(0 "F.Cu" signal "TOP")
		(4 "In1.Cu" signal "L2GND")
		(6 "In2.Cu" signal "L3")
		(8 "In3.Cu" signal "L4GND")
		(10 "In4.Cu" signal "L5")
		(12 "In5.Cu" signal "L6VCC")
		(14 "In6.Cu" signal "L7VCC")
		(16 "In7.Cu" signal "L8")
		(18 "In8.Cu" signal "L9GND")
		(20 "In9.Cu" signal "L10")
		(22 "In10.Cu" signal "L11GND")
		(2 "B.Cu" signal "BOTTOM")
		(9 "F.Adhes" user "F.Adhesive")
		(11 "B.Adhes" user "B.Adhesive")
		(13 "F.Paste" user "Package Geometry/Pastemask Top")
		(15 "B.Paste" user "Package Geometry/Pastemask Bottom")
		(5 "F.SilkS" user "Ref Des/Silkscreen Top")
		(7 "B.SilkS" user "Ref Des/Silkscreen Bottom")
		(1 "F.Mask" user "Board Geometry/Soldermask Top")
		(3 "B.Mask" user "Board Geometry/Soldermask Bottom")
		(17 "Dwgs.User" user "User.Drawings")
		(19 "Cmts.User" user "User.Comments")
		(21 "Eco1.User" user "User.Eco1")
		(23 "Eco2.User" user "User.Eco2")
		(25 "Edge.Cuts" user "Board Geometry/Outline")
		(27 "Margin" user)
		(31 "F.CrtYd" user "Package Geometry/Place Bound Top")
		(29 "B.CrtYd" user "Package Geometry/Place Bound Bottom")
		(35 "F.Fab" user "Ref Des/Assembly Top")
		(33 "B.Fab" user "Ref Des/Assembly Bottom")
	)
	(footprint ""
		(layer "F.Cu")
		(at 271.526 -272.288)
		(property "Reference" "R113"
			(at 0 0 0)
			(layer "F.SilkS")
			(hide yes)
			(effects
				(font
					(size 1.27 1.27)
				)
			)
		)
		(property "Value" "4K7R2F-GP"
			(at 0.064008 -3.993896 0)
			(unlocked yes)
			(layer "F.Fab")
			(hide yes)
			(effects
				(font
					(size 1.016 1.016)
					(thickness 0.1524)
				)
			)
		)
		(property "Device Type" "R402H16"
			(at 0.064008 -5.517896 0)
			(unlocked yes)
			(layer "F.Fab")
			(hide yes)
			(effects
				(font
					(size 1.016 1.016)
					(thickness 0.1524)
				)
			)
		)
		(duplicate_pad_numbers_are_jumpers no)
		(fp_line
			(start -0.508 -0.9398)
			(end -0.508 0.9398)
			(stroke
				(width 0.1524)
				(type default)
			)
			(layer "F.SilkS")
		)
		(fp_line
			(start 0.508 -0.9398)
			(end -0.508 -0.9398)
			(stroke
				(width 0.1524)
				(type default)
			)
			(layer "F.SilkS")
		)
		(fp_rect
			(start -0.508 0.9398)
			(end 0.508 -0.9398)
			(stroke
				(width 0)
				(type default)
			)
			(fill no)
			(layer "F.CrtYd")
		)
		(fp_rect
			(start -0.508 0.9398)
			(end 0.508 -0.9398)
			(stroke
				(width 0)
				(type default)
			)
			(fill no)
			(layer "F.Fab")
		)
		(pad "1" smd custom
			(at 0 -0.4445)
			(size 0.1397 0.1397)
			(layers "F.Cu" "F.Mask" "F.Paste")
			(net "IO_EXP1_HDD_FAULT_INT_N")
			(options
				(clearance outline)
				(anchor circle)
			)
			(primitives
				(gr_poly
					(pts
						(arc
							(start -0.1778 -0.2794)
							(mid -0.249642 -0.249642)
							(end -0.2794 -0.1778)
						)
						(arc
							(start -0.2794 0.1778)
							(mid -0.249642 0.249642)
							(end -0.1778 0.2794)
						)
						(arc
							(start 0.1778 0.2794)
							(mid 0.249642 0.249642)
							(end 0.2794 0.1778)
						)
						(arc
							(start 0.2794 -0.1778)
							(mid 0.249642 -0.249642)
							(end 0.1778 -0.2794)
						)
					)
					(width 0)
					(fill yes)
				)
			)
		)
		(pad "2" smd custom
			(at 0 0.4445)
			(size 0.1397 0.1397)
			(layers "F.Cu" "F.Mask" "F.Paste")
			(net "P3V3_STBY_A")
			(options
				(clearance outline)
				(anchor circle)
			)
			(primitives
				(gr_poly
					(pts
						(arc
							(start -0.1778 -0.2794)
							(mid -0.249642 -0.249642)
							(end -0.2794 -0.1778)
						)
						(arc
							(start -0.2794 0.1778)
							(mid -0.249642 0.249642)
							(end -0.1778 0.2794)
						)
						(arc
							(start 0.1778 0.2794)
							(mid 0.249642 0.249642)
							(end 0.2794 0.1778)
						)
						(arc
							(start 0.2794 -0.1778)
							(mid 0.249642 -0.249642)
							(end 0.1778 -0.2794)
						)
					)
					(width 0)
					(fill yes)
				)
			)
		)
	)
	(footprint ""
		(layer "F.Cu")
		(at 86.096348 -161.040318 -90)
		(property "Reference" "R460"
			(at 0 0 270)
			(layer "F.SilkS")
			(hide yes)
			(effects
				(font
					(size 1.27 1.27)
				)
			)
		)
		(property "Value" "1KR2F-3-GP"
			(at 0.064008 -3.993896 270)
			(unlocked yes)
			(layer "F.Fab")
			(hide yes)
			(effects
				(font
					(size 1.016 1.016)
					(thickness 0.1524)
				)
			)
		)
		(property "Device Type" "R402H16"
			(at 0.064008 -5.517896 270)
			(unlocked yes)
			(layer "F.Fab")
			(hide yes)
			(effects
				(font
					(size 1.016 1.016)
					(thickness 0.1524)
				)
			)
		)
		(duplicate_pad_numbers_are_jumpers no)
		(fp_line
			(start -0.508 -0.9398)
			(end -0.508 0.9398)
			(stroke
				(width 0.1524)
				(type default)
			)
			(layer "F.SilkS")
		)
		(fp_line
			(start 0.508 -0.9398)
			(end -0.508 -0.9398)
			(stroke
				(width 0.1524)
				(type default)
			)
			(layer "F.SilkS")
		)
		(fp_rect
			(start -0.508 0.9398)
			(end 0.508 -0.9398)
			(stroke
				(width 0)
				(type default)
			)
			(fill no)
			(layer "F.CrtYd")
		)
		(fp_rect
			(start -0.508 0.9398)
			(end 0.508 -0.9398)
			(stroke
				(width 0)
				(type default)
			)
			(fill no)
			(layer "F.Fab")
		)
		(pad "1" smd custom
			(at 0 -0.4445 270)
			(size 0.1397 0.1397)
			(layers "F.Cu" "F.Mask" "F.Paste")
			(net "P3V3_STBY_A")
			(options
				(clearance outline)
				(anchor circle)
			)
			(primitives
				(gr_poly
					(pts
						(arc
							(start -0.1778 -0.2794)
							(mid -0.249642 -0.249642)
							(end -0.2794 -0.1778)
						)
						(arc
							(start -0.2794 0.1778)
							(mid -0.249642 0.249642)
							(end -0.1778 0.2794)
						)
						(arc
							(start 0.1778 0.2794)
							(mid 0.249642 0.249642)
							(end 0.2794 0.1778)
						)
						(arc
							(start 0.2794 -0.1778)
							(mid 0.249642 -0.249642)
							(end 0.1778 -0.2794)
						)
					)
					(width 0)
					(fill yes)
				)
			)
		)
		(pad "2" smd custom
			(at 0 0.4445 270)
			(size 0.1397 0.1397)
			(layers "F.Cu" "F.Mask" "F.Paste")
			(net "SW_PWR_R_HDD14")
			(options
				(clearance outline)
				(anchor circle)
			)
			(primitives
				(gr_poly
					(pts
						(arc
							(start -0.1778 -0.2794)
							(mid -0.249642 -0.249642)
							(end -0.2794 -0.1778)
						)
						(arc
							(start -0.2794 0.1778)
							(mid -0.249642 0.249642)
							(end -0.1778 0.2794)
						)
						(arc
							(start 0.1778 0.2794)
							(mid 0.249642 0.249642)
							(end 0.2794 0.1778)
						)
						(arc
							(start 0.2794 -0.1778)
							(mid 0.249642 -0.249642)
							(end 0.1778 -0.2794)
						)
					)
					(width 0)
					(fill yes)
				)
			)
		)
	)
	(footprint ""
		(layer "F.Cu")
		(at 401.17395 -49.443894 90)
		(property "Reference" "R882"
			(at 0 0 90)
			(layer "F.SilkS")
			(hide yes)
			(effects
				(font
					(size 1.27 1.27)
				)
			)
		)
		(property "Value" "200KR2F-L-GP"
			(at 0.064008 -3.993896 90)
			(unlocked yes)
			(layer "F.Fab")
			(hide yes)
			(effects
				(font
					(size 1.016 1.016)
					(thickness 0.1524)
				)
			)
		)
		(property "Device Type" "R402H16"
			(at 0.064008 -5.517896 90)
			(unlocked yes)
			(layer "F.Fab")
			(hide yes)
			(effects
				(font
					(size 1.016 1.016)
					(thickness 0.1524)
				)
			)
		)
		(duplicate_pad_numbers_are_jumpers no)
		(fp_line
			(start 0.508 -0.9398)
			(end -0.508 -0.9398)
			(stroke
				(width 0.1524)
				(type default)
			)
			(layer "F.SilkS")
		)
		(fp_line
			(start -0.508 -0.9398)
			(end -0.508 0.9398)
			(stroke
				(width 0.1524)
				(type default)
			)
			(layer "F.SilkS")
		)
		(fp_rect
			(start -0.508 0.9398)
			(end 0.508 -0.9398)
			(stroke
				(width 0)
				(type default)
			)
			(fill no)
			(layer "F.CrtYd")
		)
		(fp_rect
			(start -0.508 0.9398)
			(end 0.508 -0.9398)
			(stroke
				(width 0)
				(type default)
			)
			(fill no)
			(layer "F.Fab")
		)
		(pad "1" smd custom
			(at 0 -0.4445 90)
			(size 0.1397 0.1397)
			(layers "F.Cu" "F.Mask" "F.Paste")
			(net "SW_HDD_R32")
			(options
				(clearance outline)
				(anchor circle)
			)
			(primitives
				(gr_poly
					(pts
						(arc
							(start -0.1778 -0.2794)
							(mid -0.249642 -0.249642)
							(end -0.2794 -0.1778)
						)
						(arc
							(start -0.2794 0.1778)
							(mid -0.249642 0.249642)
							(end -0.1778 0.2794)
						)
						(arc
							(start 0.1778 0.2794)
							(mid 0.249642 0.249642)
							(end 0.2794 0.1778)
						)
						(arc
							(start 0.2794 -0.1778)
							(mid 0.249642 -0.249642)
							(end 0.1778 -0.2794)
						)
					)
					(width 0)
					(fill yes)
				)
			)
		)
		(pad "2" smd custom
			(at 0 0.4445 90)
			(size 0.1397 0.1397)
			(layers "F.Cu" "F.Mask" "F.Paste")
			(net "SW_HDD_N32")
			(options
				(clearance outline)
				(anchor circle)
			)
			(primitives
				(gr_poly
					(pts
						(arc
							(start -0.1778 -0.2794)
							(mid -0.249642 -0.249642)
							(end -0.2794 -0.1778)
						)
						(arc
							(start -0.2794 0.1778)
							(mid -0.249642 0.249642)
							(end -0.1778 0.2794)
						)
						(arc
							(start 0.1778 0.2794)
							(mid 0.249642 0.249642)
							(end 0.2794 0.1778)
						)
						(arc
							(start 0.2794 -0.1778)
							(mid 0.249642 -0.249642)
							(end 0.1778 -0.2794)
						)
					)
					(width 0)
					(fill yes)
				)
			)
		)
	)
	(footprint ""
		(layer "F.Cu")
		(at 272.542 -350.505014 180)
		(property "Reference" "VIA43"
			(at 0 0 180)
			(layer "F.SilkS")
			(hide yes)
			(effects
				(font
					(size 1.27 1.27)
				)
			)
		)
		(property "Value" "100OHM-8L-1D6MM-L18L16-GP"
			(at -3.7211 -4.5085 180)
			(unlocked yes)
			(layer "F.Fab")
			(hide yes)
			(effects
				(font
					(size 1.016 1.016)
					(thickness 0.1524)
				)
			)
		)
		(property "Device Type" "VIA-PCIE-4P-394076"
			(at -3.7211 -6.0325 180)
			(unlocked yes)
			(layer "F.Fab")
			(hide yes)
			(effects
				(font
					(size 1.016 1.016)
					(thickness 0.1524)
				)
			)
		)
		(duplicate_pad_numbers_are_jumpers no)
		(fp_rect
			(start -1.9685 0.381)
			(end 1.9685 -0.381)
			(stroke
				(width 0)
				(type default)
			)
			(fill no)
			(layer "F.CrtYd")
		)
		(fp_rect
			(start -1.9685 0.381)
			(end 1.9685 -0.381)
			(stroke
				(width 0)
				(type default)
			)
			(fill no)
			(layer "F.Fab")
		)
		(pad "1" thru_hole circle
			(at -1.5875 0 180)
			(size 0.508 0.508)
			(drill 0.254)
			(layers "*.Cu" "*.Mask")
			(remove_unused_layers no)
			(net "GND")
			(clearance 0.127)
			(thermal_gap 0.127)
		)
		(pad "2" thru_hole circle
			(at -0.5715 0 180)
			(size 0.508 0.508)
			(drill 0.254)
			(layers "*.Cu" "*.Mask")
			(remove_unused_layers no)
			(net "PHY_SCC_A_TO_DRV_A_5_DP")
			(clearance 0.127)
			(thermal_gap 0.127)
		)
		(pad "3" thru_hole circle
			(at 0.5715 0 180)
			(size 0.508 0.508)
			(drill 0.254)
			(layers "*.Cu" "*.Mask")
			(remove_unused_layers no)
			(net "PHY_SCC_A_TO_DRV_A_5_DN")
			(clearance 0.127)
			(thermal_gap 0.127)
		)
		(pad "4" thru_hole circle
			(at 1.5875 0 180)
			(size 0.508 0.508)
			(drill 0.254)
			(layers "*.Cu" "*.Mask")
			(remove_unused_layers no)
			(net "GND")
			(clearance 0.127)
			(thermal_gap 0.127)
		)
	)
	(footprint ""
		(layer "F.Cu")
		(at 144.700498 -275.633942)
		(property "Reference" "R239"
			(at 0 0 0)
			(layer "F.SilkS")
			(hide yes)
			(effects
				(font
					(size 1.27 1.27)
				)
			)
		)
		(property "Value" "0R2J-2-GP"
			(at 0.064008 -3.993896 0)
			(unlocked yes)
			(layer "F.Fab")
			(hide yes)
			(effects
				(font
					(size 1.016 1.016)
					(thickness 0.1524)
				)
			)
		)
		(property "Device Type" "R402H16"
			(at 0.064008 -5.517896 0)
			(unlocked yes)
			(layer "F.Fab")
			(hide yes)
			(effects
				(font
					(size 1.016 1.016)
					(thickness 0.1524)
				)
			)
		)
		(duplicate_pad_numbers_are_jumpers no)
		(fp_line
			(start -0.508 -0.9398)
			(end -0.508 0.9398)
			(stroke
				(width 0.1524)
				(type default)
			)
			(layer "F.SilkS")
		)
		(fp_line
			(start 0.508 -0.9398)
			(end -0.508 -0.9398)
			(stroke
				(width 0.1524)
				(type default)
			)
			(layer "F.SilkS")
		)
		(fp_rect
			(start -0.508 0.9398)
			(end 0.508 -0.9398)
			(stroke
				(width 0)
				(type default)
			)
			(fill no)
			(layer "F.CrtYd")
		)
		(fp_rect
			(start -0.508 0.9398)
			(end 0.508 -0.9398)
			(stroke
				(width 0)
				(type default)
			)
			(fill no)
			(layer "F.Fab")
		)
		(pad "1" smd custom
			(at 0 -0.4445)
			(size 0.1397 0.1397)
			(layers "F.Cu" "F.Mask" "F.Paste")
			(net "SW_HDD_G4")
			(options
				(clearance outline)
				(anchor circle)
			)
			(primitives
				(gr_poly
					(pts
						(arc
							(start -0.1778 -0.2794)
							(mid -0.249642 -0.249642)
							(end -0.2794 -0.1778)
						)
						(arc
							(start -0.2794 0.1778)
							(mid -0.249642 0.249642)
							(end -0.1778 0.2794)
						)
						(arc
							(start 0.1778 0.2794)
							(mid 0.249642 0.249642)
							(end 0.2794 0.1778)
						)
						(arc
							(start 0.2794 -0.1778)
							(mid 0.249642 -0.249642)
							(end 0.1778 -0.2794)
						)
					)
					(width 0)
					(fill yes)
				)
			)
		)
		(pad "2" smd custom
			(at 0 0.4445)
			(size 0.1397 0.1397)
			(layers "F.Cu" "F.Mask" "F.Paste")
			(net "SW_HDD_R4")
			(options
				(clearance outline)
				(anchor circle)
			)
			(primitives
				(gr_poly
					(pts
						(arc
							(start -0.1778 -0.2794)
							(mid -0.249642 -0.249642)
							(end -0.2794 -0.1778)
						)
						(arc
							(start -0.2794 0.1778)
							(mid -0.249642 0.249642)
							(end -0.1778 0.2794)
						)
						(arc
							(start 0.1778 0.2794)
							(mid 0.249642 0.249642)
							(end 0.2794 0.1778)
						)
						(arc
							(start 0.2794 -0.1778)
							(mid 0.249642 -0.249642)
							(end 0.1778 -0.2794)
						)
					)
					(width 0)
					(fill yes)
				)
			)
		)
	)
)
